(kicad_pcb
	(version 20260206)
	(generator "pcbnew")
	(generator_version "10.0")
	(general
		(thickness 1.6)
		(legacy_teardrops no)
	)
	(paper "A4")
	(title_block
		(title "12092022_DA0F0TMDCD0_F0T_Management_Board_D_brd_V3_OCP.brd")
		(comment 1 "Grand Teton / footprints 1362-1366 of 1440")
	)
	(layers
		(0 "F.Cu" signal "TOP")
		(4 "In1.Cu" signal "GND")
		(6 "In2.Cu" signal "IN1")
		(8 "In3.Cu" signal "GND1")
		(10 "In4.Cu" signal "IN2")
		(12 "In5.Cu" signal "VCC")
		(14 "In6.Cu" signal "VCC1")
		(16 "In7.Cu" signal "IN3")
		(18 "In8.Cu" signal "GND2")
		(20 "In9.Cu" signal "IN4")
		(22 "In10.Cu" signal "GND3")
		(2 "B.Cu" signal "BOTTOM")
		(9 "F.Adhes" user "F.Adhesive")
		(11 "B.Adhes" user "B.Adhesive")
		(13 "F.Paste" user "Package Geometry/Pastemask Top")
		(15 "B.Paste" user "Package Geometry/Pastemask Bottom")
		(5 "F.SilkS" user "Ref Des/Silkscreen Top")
		(7 "B.SilkS" user "Ref Des/Silkscreen Bottom")
		(1 "F.Mask" user "Board Geometry/Soldermask Top")
		(3 "B.Mask" user "Board Geometry/Soldermask Bottom")
		(17 "Dwgs.User" user "User.Drawings")
		(19 "Cmts.User" user "User.Comments")
		(21 "Eco1.User" user "User.Eco1")
		(23 "Eco2.User" user "User.Eco2")
		(25 "Edge.Cuts" user "Board Geometry/Outline")
		(27 "Margin" user)
		(31 "F.CrtYd" user "Package Geometry/Place Bound Top")
		(29 "B.CrtYd" user "Package Geometry/Place Bound Bottom")
		(35 "F.Fab" user "Ref Des/Assembly Top")
		(33 "B.Fab" user "Ref Des/Assembly Bottom")
	)
	(footprint ""
		(layer "B.Cu")
		(at 44.8818 -88.4936 -90)
		(property "Reference" "R712"
			(at 0 0 90)
			(layer "B.SilkS")
			(hide yes)
			(effects
				(font
					(size 1.27 1.27)
				)
				(justify mirror)
			)
		)
		(property "Value" ""
			(at 0 0 90)
			(layer "B.Fab")
			(effects
				(font
					(size 1.27 1.27)
				)
				(justify mirror)
			)
		)
		(duplicate_pad_numbers_are_jumpers no)
		(fp_line
			(start -0.7874 0.4064)
			(end 0.7874 0.4064)
			(stroke
				(width 0.1524)
				(type default)
			)
			(layer "B.SilkS")
		)
		(fp_line
			(start 0.7874 0.4064)
			(end 0.7874 -0.4064)
			(stroke
				(width 0.1524)
				(type default)
			)
			(layer "B.SilkS")
		)
		(fp_line
			(start -0.7874 -0.4064)
			(end -0.7874 0.4064)
			(stroke
				(width 0.1524)
				(type default)
			)
			(layer "B.SilkS")
		)
		(fp_line
			(start 0.7874 -0.4064)
			(end -0.7874 -0.4064)
			(stroke
				(width 0.1524)
				(type default)
			)
			(layer "B.SilkS")
		)
		(fp_line
			(start -0.67945 0.3048)
			(end -0.120396 0.3048)
			(stroke
				(width 0.1)
				(type default)
			)
			(layer "B.Fab")
		)
		(fp_line
			(start -0.120396 0.3048)
			(end -0.120396 0.2794)
			(stroke
				(width 0.1)
				(type default)
			)
			(layer "B.Fab")
		)
		(fp_line
			(start 0.12065 0.3048)
			(end 0.67945 0.3048)
			(stroke
				(width 0.1)
				(type default)
			)
			(layer "B.Fab")
		)
		(fp_line
			(start 0.67945 0.3048)
			(end 0.67945 -0.305054)
			(stroke
				(width 0.1)
				(type default)
			)
			(layer "B.Fab")
		)
		(fp_line
			(start -0.120396 0.2794)
			(end 0.12065 0.2794)
			(stroke
				(width 0.1)
				(type default)
			)
			(layer "B.Fab")
		)
		(fp_line
			(start 0.12065 0.2794)
			(end 0.12065 0.3048)
			(stroke
				(width 0.1)
				(type default)
			)
			(layer "B.Fab")
		)
		(fp_line
			(start -0.12065 -0.2794)
			(end -0.12065 -0.3048)
			(stroke
				(width 0.1)
				(type default)
			)
			(layer "B.Fab")
		)
		(fp_line
			(start 0.12065 -0.2794)
			(end -0.12065 -0.2794)
			(stroke
				(width 0.1)
				(type default)
			)
			(layer "B.Fab")
		)
		(fp_line
			(start -0.67945 -0.3048)
			(end -0.67945 0.3048)
			(stroke
				(width 0.1)
				(type default)
			)
			(layer "B.Fab")
		)
		(fp_line
			(start -0.12065 -0.3048)
			(end -0.67945 -0.3048)
			(stroke
				(width 0.1)
				(type default)
			)
			(layer "B.Fab")
		)
		(fp_line
			(start 0.12065 -0.305054)
			(end 0.12065 -0.2794)
			(stroke
				(width 0.1)
				(type default)
			)
			(layer "B.Fab")
		)
		(fp_line
			(start 0.67945 -0.305054)
			(end 0.12065 -0.305054)
			(stroke
				(width 0.1)
				(type default)
			)
			(layer "B.Fab")
		)
		(pad "1" smd circle
			(at 0.40005 0 90)
			(size 0 0)
			(layers "B.Cu" "B.Mask" "B.Paste")
			(net "P3V3_AUX")
		)
		(pad "2" smd circle
			(at -0.40005 0 90)
			(size 0 0)
			(layers "B.Cu" "B.Mask" "B.Paste")
			(net "USB3_MUX_PD")
		)
	)
	(footprint ""
		(layer "B.Cu")
		(at 40.427656 -56.436006 -90)
		(property "Reference" "C43"
			(at 0 0 90)
			(layer "B.SilkS")
			(hide yes)
			(effects
				(font
					(size 1.27 1.27)
				)
				(justify mirror)
			)
		)
		(property "Value" ""
			(at 0 0 90)
			(layer "B.Fab")
			(effects
				(font
					(size 1.27 1.27)
				)
				(justify mirror)
			)
		)
		(duplicate_pad_numbers_are_jumpers no)
		(fp_line
			(start -0.7874 0.4064)
			(end 0.7874 0.4064)
			(stroke
				(width 0.1524)
				(type default)
			)
			(layer "B.SilkS")
		)
		(fp_line
			(start 0.7874 0.4064)
			(end 0.7874 -0.4064)
			(stroke
				(width 0.1524)
				(type default)
			)
			(layer "B.SilkS")
		)
		(fp_line
			(start -0.7874 -0.4064)
			(end -0.7874 0.4064)
			(stroke
				(width 0.1524)
				(type default)
			)
			(layer "B.SilkS")
		)
		(fp_line
			(start 0.7874 -0.4064)
			(end -0.7874 -0.4064)
			(stroke
				(width 0.1524)
				(type default)
			)
			(layer "B.SilkS")
		)
		(fp_line
			(start -0.67945 0.3048)
			(end -0.120396 0.3048)
			(stroke
				(width 0.1)
				(type default)
			)
			(layer "B.Fab")
		)
		(fp_line
			(start -0.120396 0.3048)
			(end -0.120396 0.2794)
			(stroke
				(width 0.1)
				(type default)
			)
			(layer "B.Fab")
		)
		(fp_line
			(start 0.12065 0.3048)
			(end 0.67945 0.3048)
			(stroke
				(width 0.1)
				(type default)
			)
			(layer "B.Fab")
		)
		(fp_line
			(start 0.67945 0.3048)
			(end 0.67945 -0.305054)
			(stroke
				(width 0.1)
				(type default)
			)
			(layer "B.Fab")
		)
		(fp_line
			(start -0.120396 0.2794)
			(end 0.12065 0.2794)
			(stroke
				(width 0.1)
				(type default)
			)
			(layer "B.Fab")
		)
		(fp_line
			(start 0.12065 0.2794)
			(end 0.12065 0.3048)
			(stroke
				(width 0.1)
				(type default)
			)
			(layer "B.Fab")
		)
		(fp_line
			(start -0.12065 -0.2794)
			(end -0.12065 -0.3048)
			(stroke
				(width 0.1)
				(type default)
			)
			(layer "B.Fab")
		)
		(fp_line
			(start 0.12065 -0.2794)
			(end -0.12065 -0.2794)
			(stroke
				(width 0.1)
				(type default)
			)
			(layer "B.Fab")
		)
		(fp_line
			(start -0.67945 -0.3048)
			(end -0.67945 0.3048)
			(stroke
				(width 0.1)
				(type default)
			)
			(layer "B.Fab")
		)
		(fp_line
			(start -0.12065 -0.3048)
			(end -0.67945 -0.3048)
			(stroke
				(width 0.1)
				(type default)
			)
			(layer "B.Fab")
		)
		(fp_line
			(start 0.12065 -0.305054)
			(end 0.12065 -0.2794)
			(stroke
				(width 0.1)
				(type default)
			)
			(layer "B.Fab")
		)
		(fp_line
			(start 0.67945 -0.305054)
			(end 0.12065 -0.305054)
			(stroke
				(width 0.1)
				(type default)
			)
			(layer "B.Fab")
		)
		(pad "1" smd circle
			(at 0.40005 0 90)
			(size 0 0)
			(layers "B.Cu" "B.Mask" "B.Paste")
			(net "PVCCIO_PECI_BMC")
		)
		(pad "2" smd circle
			(at -0.40005 0 90)
			(size 0 0)
			(layers "B.Cu" "B.Mask" "B.Paste")
			(net "GND")
		)
	)
	(footprint ""
		(layer "B.Cu")
		(at 18.664428 -96.786954 90)
		(property "Reference" "C165"
			(at 0 0 90)
			(layer "B.SilkS")
			(hide yes)
			(effects
				(font
					(size 1.27 1.27)
				)
				(justify mirror)
			)
		)
		(property "Value" ""
			(at 0 0 90)
			(layer "B.Fab")
			(effects
				(font
					(size 1.27 1.27)
				)
				(justify mirror)
			)
		)
		(duplicate_pad_numbers_are_jumpers no)
		(fp_line
			(start 0.69215 -0.2921)
			(end -0.69215 -0.2921)
			(stroke
				(width 0.1524)
				(type default)
			)
			(layer "B.SilkS")
		)
		(fp_line
			(start -0.69215 -0.2921)
			(end -0.69215 0.2921)
			(stroke
				(width 0.1524)
				(type default)
			)
			(layer "B.SilkS")
		)
		(fp_line
			(start 0.69215 0.2921)
			(end 0.69215 -0.2921)
			(stroke
				(width 0.1524)
				(type default)
			)
			(layer "B.SilkS")
		)
		(fp_line
			(start -0.69215 0.2921)
			(end 0.69215 0.2921)
			(stroke
				(width 0.1524)
				(type default)
			)
			(layer "B.SilkS")
		)
		(fp_line
			(start 0.51435 -0.2794)
			(end -0.51435 -0.2794)
			(stroke
				(width 0.1)
				(type default)
			)
			(layer "B.Fab")
		)
		(fp_line
			(start -0.51435 -0.2794)
			(end -0.51435 0.2794)
			(stroke
				(width 0.1)
				(type default)
			)
			(layer "B.Fab")
		)
		(fp_line
			(start 0.51435 0.2794)
			(end 0.51435 -0.2794)
			(stroke
				(width 0.1)
				(type default)
			)
			(layer "B.Fab")
		)
		(fp_line
			(start -0.51435 0.2794)
			(end 0.51435 0.2794)
			(stroke
				(width 0.1)
				(type default)
			)
			(layer "B.Fab")
		)
		(pad "1" smd circle
			(at 0.40005 0 270)
			(size 0 0)
			(layers "B.Cu" "B.Mask" "B.Paste")
			(net "VCCIO2")
		)
		(pad "2" smd circle
			(at -0.40005 0 270)
			(size 0 0)
			(layers "B.Cu" "B.Mask" "B.Paste")
			(net "GND")
		)
		(zone
			(layer "B.Cu")
			(hatch none 0.5)
			(connect_pads
				(clearance 0)
			)
			(min_thickness 0.25)
			(keepout
				(tracks not_allowed)
				(vias allowed)
				(pads allowed)
				(copperpour not_allowed)
				(footprints allowed)
			)
			(placement
				(enabled no)
				(sheetname "")
			)
			(fill
				(thermal_gap 0.5)
				(thermal_bridge_width 0.5)
				(island_removal_mode 0)
			)
			(polygon
				(pts
					(xy 18.752058 -96.977454) (xy 18.810224 -96.886014) (xy 18.810224 -96.686624) (xy 18.752058 -96.596454)
					(xy 18.576798 -96.596454) (xy 18.518378 -96.686624) (xy 18.518378 -96.886014) (xy 18.576544 -96.977454)
				)
			)
		)
	)
	(footprint ""
		(layer "B.Cu")
		(at 101.2825 -54.403752 90)
		(property "Reference" "J24"
			(at -1.063752 -3.13817 270)
			(unlocked yes)
			(layer "B.SilkS")
			(effects
				(font
					(size 0.7874 0.5842)
					(thickness 0.1524)
				)
				(justify left mirror)
			)
		)
		(property "Value" ""
			(at 0 0 90)
			(layer "B.Fab")
			(effects
				(font
					(size 1.27 1.27)
				)
				(justify mirror)
			)
		)
		(duplicate_pad_numbers_are_jumpers no)
		(fp_line
			(start 1.2192 -2.1082)
			(end -1.2192 -2.1082)
			(stroke
				(width 0.1524)
				(type default)
			)
			(layer "B.SilkS")
		)
		(fp_line
			(start -1.2192 -2.1082)
			(end -1.2192 -0.466598)
			(stroke
				(width 0.1524)
				(type default)
			)
			(layer "B.SilkS")
		)
		(fp_line
			(start -1.2192 0.468122)
			(end -1.2192 2.1082)
			(stroke
				(width 0.1524)
				(type default)
			)
			(layer "B.SilkS")
		)
		(fp_line
			(start 1.2192 2.1082)
			(end 1.2192 -2.1082)
			(stroke
				(width 0.1524)
				(type default)
			)
			(layer "B.SilkS")
		)
		(fp_line
			(start -1.2192 2.1082)
			(end 1.2192 2.1082)
			(stroke
				(width 0.1524)
				(type default)
			)
			(layer "B.SilkS")
		)
		(pad "" np_thru_hole circle
			(at -3.4671 -1.27)
			(size 1.0414 1.0414)
			(drill 1.0414)
			(layers "*.Cu" "*.Mask")
			(clearance 0.381)
			(thermal_gap 0.381)
		)
		(pad "" np_thru_hole circle
			(at -3.4671 1.27)
			(size 1.0414 1.0414)
			(drill 1.0414)
			(layers "*.Cu" "*.Mask")
			(clearance 0.381)
			(thermal_gap 0.381)
		)
		(pad "" np_thru_hole circle
			(at 2.8829 -1.27)
			(size 1.0414 1.0414)
			(drill 1.0414)
			(layers "*.Cu" "*.Mask")
			(clearance 0.381)
			(thermal_gap 0.381)
		)
		(pad "" np_thru_hole circle
			(at 2.8829 1.27)
			(size 1.0414 1.0414)
			(drill 1.0414)
			(layers "*.Cu" "*.Mask")
			(clearance 0.381)
			(thermal_gap 0.381)
		)
		(pad "1" smd rect
			(at -0.8255 -0.249936)
			(size 0.3048 0.508)
			(layers "B.Cu" "B.Mask" "B.Paste")
			(net "85_10INCH_BOT_DP")
		)
		(pad "2" smd rect
			(at -0.8255 0.249936)
			(size 0.3048 0.508)
			(layers "B.Cu" "B.Mask" "B.Paste")
			(net "85_10INCH_BOT_DN")
		)
		(pad "3" smd circle
			(at 0 0 270)
			(size 0 0)
			(layers "B.Cu" "B.Mask" "B.Paste")
			(net "GND_P1")
		)
		(zone
			(layers "F.Cu" "B.Cu" "In1.Cu" "In2.Cu" "In3.Cu" "In4.Cu" "In5.Cu" "In6.Cu"
				"In7.Cu" "In8.Cu" "In9.Cu" "In10.Cu"
			)
			(hatch none 0.5)
			(connect_pads
				(clearance 0)
			)
			(min_thickness 0.25)
			(keepout
				(tracks not_allowed)
				(vias allowed)
				(pads allowed)
				(copperpour not_allowed)
				(footprints allowed)
			)
			(placement
				(enabled no)
				(sheetname "")
			)
			(fill
				(thermal_gap 0.5)
				(thermal_bridge_width 0.5)
				(island_removal_mode 0)
			)
			(polygon
				(pts
					(arc
						(start 100.9396 -57.286652)
						(mid 99.0854 -57.286652)
						(end 100.9396 -57.286652)
					)
				)
			)
		)
		(zone
			(layers "F.Cu" "B.Cu" "In1.Cu" "In2.Cu" "In3.Cu" "In4.Cu" "In5.Cu" "In6.Cu"
				"In7.Cu" "In8.Cu" "In9.Cu" "In10.Cu"
			)
			(hatch none 0.5)
			(connect_pads
				(clearance 0)
			)
			(min_thickness 0.25)
			(keepout
				(tracks not_allowed)
				(vias allowed)
				(pads allowed)
				(copperpour not_allowed)
				(footprints allowed)
			)
			(placement
				(enabled no)
				(sheetname "")
			)
			(fill
				(thermal_gap 0.5)
				(thermal_bridge_width 0.5)
				(island_removal_mode 0)
			)
			(polygon
				(pts
					(arc
						(start 100.9396 -50.936652)
						(mid 99.0854 -50.936652)
						(end 100.9396 -50.936652)
					)
				)
			)
		)
		(zone
			(layers "F.Cu" "B.Cu" "In1.Cu" "In2.Cu" "In3.Cu" "In4.Cu" "In5.Cu" "In6.Cu"
				"In7.Cu" "In8.Cu" "In9.Cu" "In10.Cu"
			)
			(hatch none 0.5)
			(connect_pads
				(clearance 0)
			)
			(min_thickness 0.25)
			(keepout
				(tracks not_allowed)
				(vias allowed)
				(pads allowed)
				(copperpour not_allowed)
				(footprints allowed)
			)
			(placement
				(enabled no)
				(sheetname "")
			)
			(fill
				(thermal_gap 0.5)
				(thermal_bridge_width 0.5)
				(island_removal_mode 0)
			)
			(polygon
				(pts
					(arc
						(start 103.4796 -57.286652)
						(mid 101.6254 -57.286652)
						(end 103.4796 -57.286652)
					)
				)
			)
		)
		(zone
			(layers "F.Cu" "B.Cu" "In1.Cu" "In2.Cu" "In3.Cu" "In4.Cu" "In5.Cu" "In6.Cu"
				"In7.Cu" "In8.Cu" "In9.Cu" "In10.Cu"
			)
			(hatch none 0.5)
			(connect_pads
				(clearance 0)
			)
			(min_thickness 0.25)
			(keepout
				(tracks not_allowed)
				(vias allowed)
				(pads allowed)
				(copperpour not_allowed)
				(footprints allowed)
			)
			(placement
				(enabled no)
				(sheetname "")
			)
			(fill
				(thermal_gap 0.5)
				(thermal_bridge_width 0.5)
				(island_removal_mode 0)
			)
			(polygon
				(pts
					(arc
						(start 103.4796 -50.936652)
						(mid 101.6254 -50.936652)
						(end 103.4796 -50.936652)
					)
				)
			)
		)
		(zone
			(layer "B.Cu")
			(hatch none 0.5)
			(connect_pads
				(clearance 0)
			)
			(min_thickness 0.25)
			(keepout
				(tracks not_allowed)
				(vias allowed)
				(pads allowed)
				(copperpour not_allowed)
				(footprints allowed)
			)
			(placement
				(enabled no)
				(sheetname "")
			)
			(fill
				(thermal_gap 0.5)
				(thermal_bridge_width 0.5)
				(island_removal_mode 0)
			)
			(polygon
				(pts
					(xy 100.73386 -53.286152) (xy 100.829364 -53.286152) (xy 100.829364 -53.883052) (xy 101.235764 -53.883052)
					(xy 101.235764 -53.286152) (xy 101.329236 -53.286152) (xy 101.329236 -53.883052) (xy 101.735636 -53.883052)
					(xy 101.735636 -53.286152) (xy 101.83114 -53.286152) (xy 101.83114 -53.984652) (xy 100.73386 -53.984652)
				)
			)
		)
	)
	(footprint ""
		(layer "B.Cu")
		(at 41.314878 -30.816804 90)
		(property "Reference" "R688"
			(at 0 0 90)
			(layer "B.SilkS")
			(hide yes)
			(effects
				(font
					(size 1.27 1.27)
				)
				(justify mirror)
			)
		)
		(property "Value" ""
			(at 0 0 90)
			(layer "B.Fab")
			(effects
				(font
					(size 1.27 1.27)
				)
				(justify mirror)
			)
		)
		(duplicate_pad_numbers_are_jumpers no)
		(fp_line
			(start 0.7874 -0.4064)
			(end -0.7874 -0.4064)
			(stroke
				(width 0.1524)
				(type default)
			)
			(layer "B.SilkS")
		)
		(fp_line
			(start -0.7874 -0.4064)
			(end -0.7874 0.4064)
			(stroke
				(width 0.1524)
				(type default)
			)
			(layer "B.SilkS")
		)
		(fp_line
			(start 0.7874 0.4064)
			(end 0.7874 -0.4064)
			(stroke
				(width 0.1524)
				(type default)
			)
			(layer "B.SilkS")
		)
		(fp_line
			(start -0.7874 0.4064)
			(end 0.7874 0.4064)
			(stroke
				(width 0.1524)
				(type default)
			)
			(layer "B.SilkS")
		)
		(fp_line
			(start 0.67945 -0.305054)
			(end 0.12065 -0.305054)
			(stroke
				(width 0.1)
				(type default)
			)
			(layer "B.Fab")
		)
		(fp_line
			(start 0.12065 -0.305054)
			(end 0.12065 -0.2794)
			(stroke
				(width 0.1)
				(type default)
			)
			(layer "B.Fab")
		)
		(fp_line
			(start -0.12065 -0.3048)
			(end -0.67945 -0.3048)
			(stroke
				(width 0.1)
				(type default)
			)
			(layer "B.Fab")
		)
		(fp_line
			(start -0.67945 -0.3048)
			(end -0.67945 0.3048)
			(stroke
				(width 0.1)
				(type default)
			)
			(layer "B.Fab")
		)
		(fp_line
			(start 0.12065 -0.2794)
			(end -0.12065 -0.2794)
			(stroke
				(width 0.1)
				(type default)
			)
			(layer "B.Fab")
		)
		(fp_line
			(start -0.12065 -0.2794)
			(end -0.12065 -0.3048)
			(stroke
				(width 0.1)
				(type default)
			)
			(layer "B.Fab")
		)
		(fp_line
			(start 0.12065 0.2794)
			(end 0.12065 0.3048)
			(stroke
				(width 0.1)
				(type default)
			)
			(layer "B.Fab")
		)
		(fp_line
			(start -0.120396 0.2794)
			(end 0.12065 0.2794)
			(stroke
				(width 0.1)
				(type default)
			)
			(layer "B.Fab")
		)
		(fp_line
			(start 0.67945 0.3048)
			(end 0.67945 -0.305054)
			(stroke
				(width 0.1)
				(type default)
			)
			(layer "B.Fab")
		)
		(fp_line
			(start 0.12065 0.3048)
			(end 0.67945 0.3048)
			(stroke
				(width 0.1)
				(type default)
			)
			(layer "B.Fab")
		)
		(fp_line
			(start -0.120396 0.3048)
			(end -0.120396 0.2794)
			(stroke
				(width 0.1)
				(type default)
			)
			(layer "B.Fab")
		)
		(fp_line
			(start -0.67945 0.3048)
			(end -0.120396 0.3048)
			(stroke
				(width 0.1)
				(type default)
			)
			(layer "B.Fab")
		)
		(pad "1" smd circle
			(at 0.40005 0 270)
			(size 0 0)
			(layers "B.Cu" "B.Mask" "B.Paste")
			(net "RST_SGPIO_RESET_BMC_N")
		)
		(pad "2" smd circle
			(at -0.40005 0 270)
			(size 0 0)
			(layers "B.Cu" "B.Mask" "B.Paste")
			(net "RST_SGPIO_RESET_N")
		)
	)
)
